(kicad_pcb
	(version 20260206)
	(generator "pcbnew")
	(generator_version "10.0")
	(general
		(thickness 1.6)
		(legacy_teardrops no)
	)
	(paper "A4")
	(title_block
		(title "Wiwynn_Tioga_Pass_MB.brd")
		(comment 1 "Tioga Pass / footprints 3462-3468 of 4770")
	)
	(layers
		(0 "F.Cu" signal "TOP")
		(4 "In1.Cu" signal "L2GND")
		(6 "In2.Cu" signal "L3")
		(8 "In3.Cu" signal "L4GND")
		(10 "In4.Cu" signal "L5")
		(12 "In5.Cu" signal "L6GND")
		(14 "In6.Cu" signal "L7VCC")
		(16 "In7.Cu" signal "L8VCC")
		(18 "In8.Cu" signal "L9GND")
		(20 "In9.Cu" signal "L10")
		(22 "In10.Cu" signal "L11GND")
		(24 "In11.Cu" signal "L12")
		(26 "In12.Cu" signal "L13GND")
		(2 "B.Cu" signal "BOTTOM")
		(9 "F.Adhes" user "F.Adhesive")
		(11 "B.Adhes" user "B.Adhesive")
		(13 "F.Paste" user "Package Geometry/Pastemask Top")
		(15 "B.Paste" user "Package Geometry/Pastemask Bottom")
		(5 "F.SilkS" user "Ref Des/Silkscreen Top")
		(7 "B.SilkS" user "Ref Des/Silkscreen Bottom")
		(1 "F.Mask" user "Board Geometry/Soldermask Top")
		(3 "B.Mask" user "Board Geometry/Soldermask Bottom")
		(17 "Dwgs.User" user "User.Drawings")
		(19 "Cmts.User" user "User.Comments")
		(21 "Eco1.User" user "User.Eco1")
		(23 "Eco2.User" user "User.Eco2")
		(25 "Edge.Cuts" user "Board Geometry/Outline")
		(27 "Margin" user)
		(31 "F.CrtYd" user "Package Geometry/Place Bound Top")
		(29 "B.CrtYd" user "Package Geometry/Place Bound Bottom")
		(35 "F.Fab" user "Ref Des/Assembly Top")
		(33 "B.Fab" user "Ref Des/Assembly Bottom")
	)
	(footprint ""
		(layer "B.Cu")
		(at 454.311258 -31.999174 90)
		(property "Reference" "R8D25"
			(at 0 0 90)
			(layer "B.SilkS")
			(hide yes)
			(effects
				(font
					(size 1.27 1.27)
				)
				(justify mirror)
			)
		)
		(property "Value" ""
			(at 0 0 90)
			(layer "B.Fab")
			(effects
				(font
					(size 1.27 1.27)
				)
				(justify mirror)
			)
		)
		(duplicate_pad_numbers_are_jumpers no)
		(fp_poly
			(pts
				(xy 0.2794 -0.1016) (xy -0.2794 -0.1016) (xy -0.2794 0.9906) (xy 0.2794 0.9906)
			)
			(stroke
				(width 0)
				(type default)
			)
			(fill no)
			(layer "B.CrtYd")
		)
		(fp_line
			(start 0.2794 -0.1016)
			(end 0.2794 0.9906)
			(stroke
				(width 0.1)
				(type default)
			)
			(layer "B.Fab")
		)
		(fp_line
			(start -0.2794 -0.1016)
			(end 0.2794 -0.1016)
			(stroke
				(width 0.1)
				(type default)
			)
			(layer "B.Fab")
		)
		(fp_line
			(start 0.2794 0.9906)
			(end -0.2794 0.9906)
			(stroke
				(width 0.1)
				(type default)
			)
			(layer "B.Fab")
		)
		(fp_line
			(start -0.2794 0.9906)
			(end -0.2794 -0.1016)
			(stroke
				(width 0.1)
				(type default)
			)
			(layer "B.Fab")
		)
		(pad "1" smd rect
			(at 0 0 270)
			(size 0.508 0.508)
			(layers "B.Cu" "B.Mask" "B.Paste")
			(net "P3V3_STBY")
		)
		(pad "2" smd rect
			(at 0 0.889 270)
			(size 0.508 0.508)
			(layers "B.Cu" "B.Mask" "B.Paste")
			(net "RST_BMC_SRST_R2_N")
		)
		(zone
			(layer "B.Cu")
			(hatch none 0.5)
			(connect_pads
				(clearance 0)
			)
			(min_thickness 0.25)
			(keepout
				(tracks allowed)
				(vias not_allowed)
				(pads allowed)
				(copperpour not_allowed)
				(footprints allowed)
			)
			(placement
				(enabled no)
				(sheetname "")
			)
			(fill
				(thermal_gap 0.5)
				(thermal_bridge_width 0.5)
				(island_removal_mode 0)
			)
			(polygon
				(pts
					(xy 454.565258 -32.253174) (xy 454.565258 -31.745174) (xy 454.946258 -31.745174) (xy 454.946258 -32.253174)
				)
			)
		)
		(zone
			(layer "B.Cu")
			(hatch none 0.5)
			(connect_pads
				(clearance 0)
			)
			(min_thickness 0.25)
			(keepout
				(tracks not_allowed)
				(vias allowed)
				(pads allowed)
				(copperpour not_allowed)
				(footprints allowed)
			)
			(placement
				(enabled no)
				(sheetname "")
			)
			(fill
				(thermal_gap 0.5)
				(thermal_bridge_width 0.5)
				(island_removal_mode 0)
			)
			(polygon
				(pts
					(xy 454.946258 -32.253174) (xy 454.946258 -31.745174) (xy 454.565258 -31.745174) (xy 454.565258 -32.253174)
				)
			)
		)
	)
	(footprint ""
		(layer "B.Cu")
		(at 349.377 -16.51 180)
		(property "Reference" "R3T13"
			(at 0 0 0)
			(layer "B.SilkS")
			(hide yes)
			(effects
				(font
					(size 1.27 1.27)
				)
				(justify mirror)
			)
		)
		(property "Value" ""
			(at 0 0 0)
			(layer "B.Fab")
			(effects
				(font
					(size 1.27 1.27)
				)
				(justify mirror)
			)
		)
		(duplicate_pad_numbers_are_jumpers no)
		(fp_rect
			(start -0.2794 0.9906)
			(end 0.2794 -0.1016)
			(stroke
				(width 0)
				(type default)
			)
			(fill no)
			(layer "B.CrtYd")
		)
		(fp_line
			(start 0.2794 0.9906)
			(end -0.2794 0.9906)
			(stroke
				(width 0.1)
				(type default)
			)
			(layer "B.Fab")
		)
		(fp_line
			(start 0.2794 -0.1016)
			(end 0.2794 0.9906)
			(stroke
				(width 0.1)
				(type default)
			)
			(layer "B.Fab")
		)
		(fp_line
			(start -0.2794 0.9906)
			(end -0.2794 -0.1016)
			(stroke
				(width 0.1)
				(type default)
			)
			(layer "B.Fab")
		)
		(fp_line
			(start -0.2794 -0.1016)
			(end 0.2794 -0.1016)
			(stroke
				(width 0.1)
				(type default)
			)
			(layer "B.Fab")
		)
		(pad "1" smd rect
			(at 0 0)
			(size 0.508 0.508)
			(layers "B.Cu" "B.Mask" "B.Paste")
			(net "P3V3_STBY")
		)
		(pad "2" smd rect
			(at 0 0.889)
			(size 0.508 0.508)
			(layers "B.Cu" "B.Mask" "B.Paste")
			(net "VR_PVDDQ_ABC_VDD")
		)
		(zone
			(layer "B.Cu")
			(hatch none 0.5)
			(connect_pads
				(clearance 0)
			)
			(min_thickness 0.25)
			(keepout
				(tracks allowed)
				(vias not_allowed)
				(pads allowed)
				(copperpour not_allowed)
				(footprints allowed)
			)
			(placement
				(enabled no)
				(sheetname "")
			)
			(fill
				(thermal_gap 0.5)
				(thermal_bridge_width 0.5)
				(island_removal_mode 0)
			)
			(polygon
				(pts
					(xy 349.631 -17.145) (xy 349.123 -17.145) (xy 349.123 -16.764) (xy 349.631 -16.764)
				)
			)
		)
		(zone
			(layer "B.Cu")
			(hatch none 0.5)
			(connect_pads
				(clearance 0)
			)
			(min_thickness 0.25)
			(keepout
				(tracks not_allowed)
				(vias allowed)
				(pads allowed)
				(copperpour not_allowed)
				(footprints allowed)
			)
			(placement
				(enabled no)
				(sheetname "")
			)
			(fill
				(thermal_gap 0.5)
				(thermal_bridge_width 0.5)
				(island_removal_mode 0)
			)
			(polygon
				(pts
					(xy 349.631 -17.145) (xy 349.123 -17.145) (xy 349.123 -16.764) (xy 349.631 -16.764)
				)
			)
		)
	)
	(footprint ""
		(layer "B.Cu")
		(at 470.027 -57.912 -90)
		(property "Reference" "R1R20"
			(at 0 0 90)
			(layer "B.SilkS")
			(hide yes)
			(effects
				(font
					(size 1.27 1.27)
				)
				(justify mirror)
			)
		)
		(property "Value" ""
			(at 0 0 90)
			(layer "B.Fab")
			(effects
				(font
					(size 1.27 1.27)
				)
				(justify mirror)
			)
		)
		(duplicate_pad_numbers_are_jumpers no)
		(fp_poly
			(pts
				(xy 0.2794 -0.1016) (xy -0.2794 -0.1016) (xy -0.2794 0.9906) (xy 0.2794 0.9906)
			)
			(stroke
				(width 0)
				(type default)
			)
			(fill no)
			(layer "B.CrtYd")
		)
		(fp_line
			(start -0.2794 0.9906)
			(end -0.2794 -0.1016)
			(stroke
				(width 0.1)
				(type default)
			)
			(layer "B.Fab")
		)
		(fp_line
			(start 0.2794 0.9906)
			(end -0.2794 0.9906)
			(stroke
				(width 0.1)
				(type default)
			)
			(layer "B.Fab")
		)
		(fp_line
			(start -0.2794 -0.1016)
			(end 0.2794 -0.1016)
			(stroke
				(width 0.1)
				(type default)
			)
			(layer "B.Fab")
		)
		(fp_line
			(start 0.2794 -0.1016)
			(end 0.2794 0.9906)
			(stroke
				(width 0.1)
				(type default)
			)
			(layer "B.Fab")
		)
		(pad "1" smd rect
			(at 0 0 90)
			(size 0.508 0.508)
			(layers "B.Cu" "B.Mask" "B.Paste")
			(net "P3V3_STBY")
		)
		(pad "2" smd rect
			(at 0 0.889 90)
			(size 0.508 0.508)
			(layers "B.Cu" "B.Mask" "B.Paste")
			(net "SMB_PCH_MEZZ_LOM1_SCL")
		)
		(zone
			(layer "B.Cu")
			(hatch none 0.5)
			(connect_pads
				(clearance 0)
			)
			(min_thickness 0.25)
			(keepout
				(tracks not_allowed)
				(vias allowed)
				(pads allowed)
				(copperpour not_allowed)
				(footprints allowed)
			)
			(placement
				(enabled no)
				(sheetname "")
			)
			(fill
				(thermal_gap 0.5)
				(thermal_bridge_width 0.5)
				(island_removal_mode 0)
			)
			(polygon
				(pts
					(xy 469.392 -57.658) (xy 469.392 -58.166) (xy 469.773 -58.166) (xy 469.773 -57.658)
				)
			)
		)
		(zone
			(layer "B.Cu")
			(hatch none 0.5)
			(connect_pads
				(clearance 0)
			)
			(min_thickness 0.25)
			(keepout
				(tracks allowed)
				(vias not_allowed)
				(pads allowed)
				(copperpour not_allowed)
				(footprints allowed)
			)
			(placement
				(enabled no)
				(sheetname "")
			)
			(fill
				(thermal_gap 0.5)
				(thermal_bridge_width 0.5)
				(island_removal_mode 0)
			)
			(polygon
				(pts
					(xy 469.773 -57.658) (xy 469.773 -58.166) (xy 469.392 -58.166) (xy 469.392 -57.658)
				)
			)
		)
	)
	(footprint ""
		(layer "B.Cu")
		(at 111.000032 -145.0086 90)
		(property "Reference" "C7L4"
			(at -1.848866 0.752348 90)
			(unlocked yes)
			(layer "B.SilkS")
			(effects
				(font
					(size 1.27 0.9652)
					(thickness 0.1524)
				)
				(justify mirror)
			)
		)
		(property "Value" ""
			(at 0 0 90)
			(layer "B.Fab")
			(effects
				(font
					(size 1.27 1.27)
				)
				(justify mirror)
			)
		)
		(duplicate_pad_numbers_are_jumpers no)
		(fp_rect
			(start 0.500126 1.598422)
			(end -0.500126 -0.201422)
			(stroke
				(width 0)
				(type default)
			)
			(fill no)
			(layer "B.CrtYd")
		)
		(fp_line
			(start 0.500126 -0.201422)
			(end -0.500126 -0.201422)
			(stroke
				(width 0.1)
				(type default)
			)
			(layer "B.Fab")
		)
		(fp_line
			(start -0.500126 -0.201422)
			(end -0.500126 1.598422)
			(stroke
				(width 0.1)
				(type default)
			)
			(layer "B.Fab")
		)
		(fp_line
			(start 0.500126 1.598422)
			(end 0.500126 -0.201422)
			(stroke
				(width 0.1)
				(type default)
			)
			(layer "B.Fab")
		)
		(fp_line
			(start -0.500126 1.598422)
			(end 0.500126 1.598422)
			(stroke
				(width 0.1)
				(type default)
			)
			(layer "B.Fab")
		)
		(pad "1" smd rect
			(at 0 0)
			(size 0.889 0.9906)
			(layers "B.Cu" "B.Mask" "B.Paste")
			(net "PVDDQ_KLM")
		)
		(pad "2" smd rect
			(at 0 1.397)
			(size 0.889 0.9906)
			(layers "B.Cu" "B.Mask" "B.Paste")
			(net "GND")
		)
		(zone
			(layer "B.Cu")
			(hatch none 0.5)
			(connect_pads
				(clearance 0)
			)
			(min_thickness 0.25)
			(keepout
				(tracks allowed)
				(vias not_allowed)
				(pads allowed)
				(copperpour not_allowed)
				(footprints allowed)
			)
			(placement
				(enabled no)
				(sheetname "")
			)
			(fill
				(thermal_gap 0.5)
				(thermal_bridge_width 0.5)
				(island_removal_mode 0)
			)
			(polygon
				(pts
					(xy 111.952532 -145.5039) (xy 111.444532 -145.5039) (xy 111.444532 -144.5133) (xy 111.952532 -144.5133)
				)
			)
		)
		(zone
			(layer "B.Cu")
			(hatch none 0.5)
			(connect_pads
				(clearance 0)
			)
			(min_thickness 0.25)
			(keepout
				(tracks not_allowed)
				(vias allowed)
				(pads allowed)
				(copperpour not_allowed)
				(footprints allowed)
			)
			(placement
				(enabled no)
				(sheetname "")
			)
			(fill
				(thermal_gap 0.5)
				(thermal_bridge_width 0.5)
				(island_removal_mode 0)
			)
			(polygon
				(pts
					(xy 111.952532 -145.5039) (xy 111.444532 -145.5039) (xy 111.444532 -144.5133) (xy 111.952532 -144.5133)
				)
			)
		)
	)
	(footprint ""
		(layer "B.Cu")
		(at 397.886174 -33.262316)
		(property "Reference" "R2T35"
			(at 0 0 0)
			(layer "B.SilkS")
			(hide yes)
			(effects
				(font
					(size 1.27 1.27)
				)
				(justify mirror)
			)
		)
		(property "Value" ""
			(at 0 0 0)
			(layer "B.Fab")
			(effects
				(font
					(size 1.27 1.27)
				)
				(justify mirror)
			)
		)
		(duplicate_pad_numbers_are_jumpers no)
		(fp_poly
			(pts
				(xy 0.2794 -0.1016) (xy -0.2794 -0.1016) (xy -0.2794 0.9906) (xy 0.2794 0.9906)
			)
			(stroke
				(width 0)
				(type default)
			)
			(fill no)
			(layer "B.CrtYd")
		)
		(fp_line
			(start -0.2794 -0.1016)
			(end 0.2794 -0.1016)
			(stroke
				(width 0.1)
				(type default)
			)
			(layer "B.Fab")
		)
		(fp_line
			(start -0.2794 0.9906)
			(end -0.2794 -0.1016)
			(stroke
				(width 0.1)
				(type default)
			)
			(layer "B.Fab")
		)
		(fp_line
			(start 0.2794 -0.1016)
			(end 0.2794 0.9906)
			(stroke
				(width 0.1)
				(type default)
			)
			(layer "B.Fab")
		)
		(fp_line
			(start 0.2794 0.9906)
			(end -0.2794 0.9906)
			(stroke
				(width 0.1)
				(type default)
			)
			(layer "B.Fab")
		)
		(pad "1" smd rect
			(at 0 0 180)
			(size 0.508 0.508)
			(layers "B.Cu" "B.Mask" "B.Paste")
			(net "P3V3_STBY")
		)
		(pad "2" smd rect
			(at 0 0.889 180)
			(size 0.508 0.508)
			(layers "B.Cu" "B.Mask" "B.Paste")
			(net "RST_BMC_SYSRST_BTN_OUT_N")
		)
		(zone
			(layer "B.Cu")
			(hatch none 0.5)
			(connect_pads
				(clearance 0)
			)
			(min_thickness 0.25)
			(keepout
				(tracks allowed)
				(vias not_allowed)
				(pads allowed)
				(copperpour not_allowed)
				(footprints allowed)
			)
			(placement
				(enabled no)
				(sheetname "")
			)
			(fill
				(thermal_gap 0.5)
				(thermal_bridge_width 0.5)
				(island_removal_mode 0)
			)
			(polygon
				(pts
					(xy 398.140174 -33.008316) (xy 397.632174 -33.008316) (xy 397.632174 -32.627316) (xy 398.140174 -32.627316)
				)
			)
		)
		(zone
			(layer "B.Cu")
			(hatch none 0.5)
			(connect_pads
				(clearance 0)
			)
			(min_thickness 0.25)
			(keepout
				(tracks not_allowed)
				(vias allowed)
				(pads allowed)
				(copperpour not_allowed)
				(footprints allowed)
			)
			(placement
				(enabled no)
				(sheetname "")
			)
			(fill
				(thermal_gap 0.5)
				(thermal_bridge_width 0.5)
				(island_removal_mode 0)
			)
			(polygon
				(pts
					(xy 398.140174 -32.627316) (xy 397.632174 -32.627316) (xy 397.632174 -33.008316) (xy 398.140174 -33.008316)
				)
			)
		)
	)
	(footprint ""
		(layer "B.Cu")
		(at 470.4715 -138.557 90)
		(property "Reference" "R1L27"
			(at 0 0 90)
			(layer "B.SilkS")
			(hide yes)
			(effects
				(font
					(size 1.27 1.27)
				)
				(justify mirror)
			)
		)
		(property "Value" ""
			(at 0 0 90)
			(layer "B.Fab")
			(effects
				(font
					(size 1.27 1.27)
				)
				(justify mirror)
			)
		)
		(duplicate_pad_numbers_are_jumpers no)
		(fp_poly
			(pts
				(xy 0.2794 -0.1016) (xy -0.2794 -0.1016) (xy -0.2794 0.9906) (xy 0.2794 0.9906)
			)
			(stroke
				(width 0)
				(type default)
			)
			(fill no)
			(layer "B.CrtYd")
		)
		(fp_line
			(start 0.2794 -0.1016)
			(end 0.2794 0.9906)
			(stroke
				(width 0.1)
				(type default)
			)
			(layer "B.Fab")
		)
		(fp_line
			(start -0.2794 -0.1016)
			(end 0.2794 -0.1016)
			(stroke
				(width 0.1)
				(type default)
			)
			(layer "B.Fab")
		)
		(fp_line
			(start 0.2794 0.9906)
			(end -0.2794 0.9906)
			(stroke
				(width 0.1)
				(type default)
			)
			(layer "B.Fab")
		)
		(fp_line
			(start -0.2794 0.9906)
			(end -0.2794 -0.1016)
			(stroke
				(width 0.1)
				(type default)
			)
			(layer "B.Fab")
		)
		(pad "1" smd rect
			(at 0 0 270)
			(size 0.508 0.508)
			(layers "B.Cu" "B.Mask" "B.Paste")
			(net "P3V3_STBY")
		)
		(pad "2" smd rect
			(at 0 0.889 270)
			(size 0.508 0.508)
			(layers "B.Cu" "B.Mask" "B.Paste")
			(net "FP_PWR_BTN_R_N")
		)
		(zone
			(layer "B.Cu")
			(hatch none 0.5)
			(connect_pads
				(clearance 0)
			)
			(min_thickness 0.25)
			(keepout
				(tracks allowed)
				(vias not_allowed)
				(pads allowed)
				(copperpour not_allowed)
				(footprints allowed)
			)
			(placement
				(enabled no)
				(sheetname "")
			)
			(fill
				(thermal_gap 0.5)
				(thermal_bridge_width 0.5)
				(island_removal_mode 0)
			)
			(polygon
				(pts
					(xy 470.7255 -138.811) (xy 470.7255 -138.303) (xy 471.1065 -138.303) (xy 471.1065 -138.811)
				)
			)
		)
		(zone
			(layer "B.Cu")
			(hatch none 0.5)
			(connect_pads
				(clearance 0)
			)
			(min_thickness 0.25)
			(keepout
				(tracks not_allowed)
				(vias allowed)
				(pads allowed)
				(copperpour not_allowed)
				(footprints allowed)
			)
			(placement
				(enabled no)
				(sheetname "")
			)
			(fill
				(thermal_gap 0.5)
				(thermal_bridge_width 0.5)
				(island_removal_mode 0)
			)
			(polygon
				(pts
					(xy 471.1065 -138.811) (xy 471.1065 -138.303) (xy 470.7255 -138.303) (xy 470.7255 -138.811)
				)
			)
		)
	)
	(footprint ""
		(layer "B.Cu")
		(at 476.885 -34.0995)
		(property "Reference" "C2T38"
			(at 0 0 0)
			(layer "B.SilkS")
			(hide yes)
			(effects
				(font
					(size 1.27 1.27)
				)
				(justify mirror)
			)
		)
		(property "Value" ""
			(at 0 0 0)
			(layer "B.Fab")
			(effects
				(font
					(size 1.27 1.27)
				)
				(justify mirror)
			)
		)
		(duplicate_pad_numbers_are_jumpers no)
		(fp_poly
			(pts
				(xy -0.3048 -0.1016) (xy -0.3048 0.9906) (xy 0.3048 0.9906) (xy 0.3048 -0.1016)
			)
			(stroke
				(width 0)
				(type default)
			)
			(fill no)
			(layer "B.CrtYd")
		)
		(fp_line
			(start -0.3048 -0.1016)
			(end 0.3048 -0.1016)
			(stroke
				(width 0.1)
				(type default)
			)
			(layer "B.Fab")
		)
		(fp_line
			(start -0.3048 0.9906)
			(end -0.3048 -0.1016)
			(stroke
				(width 0.1)
				(type default)
			)
			(layer "B.Fab")
		)
		(fp_line
			(start 0.3048 -0.1016)
			(end 0.3048 0.9906)
			(stroke
				(width 0.1)
				(type default)
			)
			(layer "B.Fab")
		)
		(fp_line
			(start 0.3048 0.9906)
			(end -0.3048 0.9906)
			(stroke
				(width 0.1)
				(type default)
			)
			(layer "B.Fab")
		)
		(pad "1" smd rect
			(at 0 0 180)
			(size 0.508 0.508)
			(layers "B.Cu" "B.Mask" "B.Paste")
			(net "P3V3_STBY_MNG_RMII")
		)
		(pad "2" smd rect
			(at 0 0.889 180)
			(size 0.508 0.508)
			(layers "B.Cu" "B.Mask" "B.Paste")
			(net "GND")
		)
		(zone
			(layer "B.Cu")
			(hatch none 0.5)
			(connect_pads
				(clearance 0)
			)
			(min_thickness 0.25)
			(keepout
				(tracks allowed)
				(vias not_allowed)
				(pads allowed)
				(copperpour not_allowed)
				(footprints allowed)
			)
			(placement
				(enabled no)
				(sheetname "")
			)
			(fill
				(thermal_gap 0.5)
				(thermal_bridge_width 0.5)
				(island_removal_mode 0)
			)
			(polygon
				(pts
					(xy 477.139 -33.8455) (xy 476.631 -33.8455) (xy 476.631 -33.4645) (xy 477.139 -33.4645)
				)
			)
		)
		(zone
			(layer "B.Cu")
			(hatch none 0.5)
			(connect_pads
				(clearance 0)
			)
			(min_thickness 0.25)
			(keepout
				(tracks not_allowed)
				(vias allowed)
				(pads allowed)
				(copperpour not_allowed)
				(footprints allowed)
			)
			(placement
				(enabled no)
				(sheetname "")
			)
			(fill
				(thermal_gap 0.5)
				(thermal_bridge_width 0.5)
				(island_removal_mode 0)
			)
			(polygon
				(pts
					(xy 477.139 -33.4645) (xy 476.631 -33.4645) (xy 476.631 -33.8455) (xy 477.139 -33.8455)
				)
			)
		)
	)
)
